# BASEBOARD_FAB2 (Tioga Pass) — schematic netlist excerpt (pin names and nets, part order shuffled) for the footprints in the layout excerpt that follows; sources: Cadence DE-HDL packaged netlist, KiCad conversion of Wiwynn_Tioga_Pass_MB.brd

C5D9  CAP_A  22.0UF 4V 20% X6S  pkg 0603V  page 220 : A = PVDDQ_DEF ; B = GND
R8E20  RES  33.2 1% CHIP  pkg 0402  page 136 : A = FM_BIOS_TOP_SWAP_SPKR_R ; B = FM_BIOS_TOP_SWAP_SPKR
C5A18  CAP_A  47UF 4V 20% X5R  pkg 0603V  page 220 : A = PVDDQ_DEF ; B = GND

(kicad_pcb
	(version 20260206)
	(generator "pcbnew")
	(generator_version "10.0")
	(general
		(thickness 1.6)
		(legacy_teardrops no)
	)
	(paper "A4")
	(title_block
		(title "Wiwynn_Tioga_Pass_MB.brd")
		(comment 1 "Tioga Pass / footprints 1911-1913 of 4770")
	)
	(layers
		(0 "F.Cu" signal "TOP")
		(4 "In1.Cu" signal "L2GND")
		(6 "In2.Cu" signal "L3")
		(8 "In3.Cu" signal "L4GND")
		(10 "In4.Cu" signal "L5")
		(12 "In5.Cu" signal "L6GND")
		(14 "In6.Cu" signal "L7VCC")
		(16 "In7.Cu" signal "L8VCC")
		(18 "In8.Cu" signal "L9GND")
		(20 "In9.Cu" signal "L10")
		(22 "In10.Cu" signal "L11GND")
		(24 "In11.Cu" signal "L12")
		(26 "In12.Cu" signal "L13GND")
		(2 "B.Cu" signal "BOTTOM")
		(9 "F.Adhes" user "F.Adhesive")
		(11 "B.Adhes" user "B.Adhesive")
		(13 "F.Paste" user "Package Geometry/Pastemask Top")
		(15 "B.Paste" user "Package Geometry/Pastemask Bottom")
		(5 "F.SilkS" user "Ref Des/Silkscreen Top")
		(7 "B.SilkS" user "Ref Des/Silkscreen Bottom")
		(1 "F.Mask" user "Board Geometry/Soldermask Top")
		(3 "B.Mask" user "Board Geometry/Soldermask Bottom")
		(17 "Dwgs.User" user "User.Drawings")
		(19 "Cmts.User" user "User.Comments")
		(21 "Eco1.User" user "User.Eco1")
		(23 "Eco2.User" user "User.Eco2")
		(25 "Edge.Cuts" user "Board Geometry/Outline")
		(27 "Margin" user)
		(31 "F.CrtYd" user "Package Geometry/Place Bound Top")
		(29 "B.CrtYd" user "Package Geometry/Place Bound Bottom")
		(35 "F.Fab" user "Ref Des/Assembly Top")
		(33 "B.Fab" user "Ref Des/Assembly Bottom")
	)
	(footprint ""
		(layer "F.Cu")
		(at 272.861532 -140.208 90)
		(property "Reference" "C5A18"
			(at 1.848866 0.752348 90)
			(unlocked yes)
			(layer "F.SilkS")
			(effects
				(font
					(size 1.27 0.9652)
					(thickness 0.1524)
				)
			)
		)
		(property "Value" ""
			(at 0 0 90)
			(layer "F.Fab")
			(effects
				(font
					(size 1.27 1.27)
				)
			)
		)
		(duplicate_pad_numbers_are_jumpers no)
		(fp_rect
			(start -0.500126 1.598422)
			(end 0.500126 -0.201422)
			(stroke
				(width 0)
				(type default)
			)
			(fill no)
			(layer "F.CrtYd")
		)
		(fp_line
			(start 0.500126 -0.201422)
			(end 0.500126 1.598422)
			(stroke
				(width 0.1)
				(type default)
			)
			(layer "F.Fab")
		)
		(fp_line
			(start -0.500126 -0.201422)
			(end 0.500126 -0.201422)
			(stroke
				(width 0.1)
				(type default)
			)
			(layer "F.Fab")
		)
		(fp_line
			(start 0.500126 1.598422)
			(end -0.500126 1.598422)
			(stroke
				(width 0.1)
				(type default)
			)
			(layer "F.Fab")
		)
		(fp_line
			(start -0.500126 1.598422)
			(end -0.500126 -0.201422)
			(stroke
				(width 0.1)
				(type default)
			)
			(layer "F.Fab")
		)
		(pad "1" smd rect
			(at 0 0)
			(size 0.889 0.9906)
			(layers "F.Cu" "F.Mask" "F.Paste")
			(net "PVDDQ_DEF")
		)
		(pad "2" smd rect
			(at 0 1.397)
			(size 0.889 0.9906)
			(layers "F.Cu" "F.Mask" "F.Paste")
			(net "GND")
		)
		(zone
			(layer "F.Cu")
			(hatch none 0.5)
			(connect_pads
				(clearance 0)
			)
			(min_thickness 0.25)
			(keepout
				(tracks allowed)
				(vias not_allowed)
				(pads allowed)
				(copperpour not_allowed)
				(footprints allowed)
			)
			(placement
				(enabled no)
				(sheetname "")
			)
			(fill
				(thermal_gap 0.5)
				(thermal_bridge_width 0.5)
				(island_removal_mode 0)
			)
			(polygon
				(pts
					(xy 273.814032 -139.7127) (xy 273.814032 -140.7033) (xy 273.306032 -140.7033) (xy 273.306032 -139.7127)
				)
			)
		)
		(zone
			(layer "F.Cu")
			(hatch none 0.5)
			(connect_pads
				(clearance 0)
			)
			(min_thickness 0.25)
			(keepout
				(tracks not_allowed)
				(vias allowed)
				(pads allowed)
				(copperpour not_allowed)
				(footprints allowed)
			)
			(placement
				(enabled no)
				(sheetname "")
			)
			(fill
				(thermal_gap 0.5)
				(thermal_bridge_width 0.5)
				(island_removal_mode 0)
			)
			(polygon
				(pts
					(xy 273.814032 -139.7127) (xy 273.814032 -140.7033) (xy 273.306032 -140.7033) (xy 273.306032 -139.7127)
				)
			)
		)
	)
	(footprint ""
		(layer "F.Cu")
		(at 414.059116 -53.707792 180)
		(property "Reference" "R8E20"
			(at 0 0 180)
			(layer "F.SilkS")
			(hide yes)
			(effects
				(font
					(size 1.27 1.27)
				)
			)
		)
		(property "Value" ""
			(at 0 0 180)
			(layer "F.Fab")
			(effects
				(font
					(size 1.27 1.27)
				)
			)
		)
		(duplicate_pad_numbers_are_jumpers no)
		(fp_poly
			(pts
				(xy -0.2794 -0.1016) (xy 0.2794 -0.1016) (xy 0.2794 0.9906) (xy -0.2794 0.9906)
			)
			(stroke
				(width 0)
				(type default)
			)
			(fill no)
			(layer "F.CrtYd")
		)
		(fp_line
			(start 0.2794 0.9906)
			(end 0.2794 -0.1016)
			(stroke
				(width 0.1)
				(type default)
			)
			(layer "F.Fab")
		)
		(fp_line
			(start 0.2794 -0.1016)
			(end -0.2794 -0.1016)
			(stroke
				(width 0.1)
				(type default)
			)
			(layer "F.Fab")
		)
		(fp_line
			(start -0.2794 0.9906)
			(end 0.2794 0.9906)
			(stroke
				(width 0.1)
				(type default)
			)
			(layer "F.Fab")
		)
		(fp_line
			(start -0.2794 -0.1016)
			(end -0.2794 0.9906)
			(stroke
				(width 0.1)
				(type default)
			)
			(layer "F.Fab")
		)
		(pad "1" smd rect
			(at 0 0 180)
			(size 0.508 0.508)
			(layers "F.Cu" "F.Mask" "F.Paste")
			(net "FM_BIOS_TOP_SWAP_SPKR_R")
		)
		(pad "2" smd rect
			(at 0 0.889 180)
			(size 0.508 0.508)
			(layers "F.Cu" "F.Mask" "F.Paste")
			(net "FM_BIOS_TOP_SWAP_SPKR")
		)
		(zone
			(layer "F.Cu")
			(hatch none 0.5)
			(connect_pads
				(clearance 0)
			)
			(min_thickness 0.25)
			(keepout
				(tracks not_allowed)
				(vias allowed)
				(pads allowed)
				(copperpour not_allowed)
				(footprints allowed)
			)
			(placement
				(enabled no)
				(sheetname "")
			)
			(fill
				(thermal_gap 0.5)
				(thermal_bridge_width 0.5)
				(island_removal_mode 0)
			)
			(polygon
				(pts
					(xy 414.313116 -54.342792) (xy 413.805116 -54.342792) (xy 413.805116 -53.961792) (xy 414.313116 -53.961792)
				)
			)
		)
		(zone
			(layer "F.Cu")
			(hatch none 0.5)
			(connect_pads
				(clearance 0)
			)
			(min_thickness 0.25)
			(keepout
				(tracks allowed)
				(vias not_allowed)
				(pads allowed)
				(copperpour not_allowed)
				(footprints allowed)
			)
			(placement
				(enabled no)
				(sheetname "")
			)
			(fill
				(thermal_gap 0.5)
				(thermal_bridge_width 0.5)
				(island_removal_mode 0)
			)
			(polygon
				(pts
					(xy 414.313116 -53.961792) (xy 413.805116 -53.961792) (xy 413.805116 -54.342792) (xy 414.313116 -54.342792)
				)
			)
		)
	)
	(footprint ""
		(layer "F.Cu")
		(at 263.525 -84.709)
		(property "Reference" "C5D9"
			(at 0 0 0)
			(layer "F.SilkS")
			(hide yes)
			(effects
				(font
					(size 1.27 1.27)
				)
			)
		)
		(property "Value" ""
			(at 0 0 0)
			(layer "F.Fab")
			(effects
				(font
					(size 1.27 1.27)
				)
			)
		)
		(duplicate_pad_numbers_are_jumpers no)
		(fp_poly
			(pts
				(xy -0.4953 -0.2032) (xy 0.4953 -0.2032) (xy 0.4953 1.6002) (xy -0.4953 1.6002)
			)
			(stroke
				(width 0)
				(type default)
			)
			(fill no)
			(layer "F.CrtYd")
		)
		(fp_line
			(start -0.4953 -0.2032)
			(end 0.4953 -0.2032)
			(stroke
				(width 0.1)
				(type default)
			)
			(layer "F.Fab")
		)
		(fp_line
			(start -0.4953 1.6002)
			(end -0.4953 -0.2032)
			(stroke
				(width 0.1)
				(type default)
			)
			(layer "F.Fab")
		)
		(fp_line
			(start 0.4953 -0.2032)
			(end 0.4953 1.6002)
			(stroke
				(width 0.1)
				(type default)
			)
			(layer "F.Fab")
		)
		(fp_line
			(start 0.4953 1.6002)
			(end -0.4953 1.6002)
			(stroke
				(width 0.1)
				(type default)
			)
			(layer "F.Fab")
		)
		(pad "1" smd rect
			(at 0 0)
			(size 0.762 0.889)
			(layers "F.Cu" "F.Mask" "F.Paste")
			(net "PVDDQ_DEF")
		)
		(pad "2" smd rect
			(at 0 1.397)
			(size 0.762 0.889)
			(layers "F.Cu" "F.Mask" "F.Paste")
			(net "GND")
		)
		(zone
			(layer "F.Cu")
			(hatch none 0.5)
			(connect_pads
				(clearance 0)
			)
			(min_thickness 0.25)
			(keepout
				(tracks not_allowed)
				(vias allowed)
				(pads allowed)
				(copperpour not_allowed)
				(footprints allowed)
			)
			(placement
				(enabled no)
				(sheetname "")
			)
			(fill
				(thermal_gap 0.5)
				(thermal_bridge_width 0.5)
				(island_removal_mode 0)
			)
			(polygon
				(pts
					(xy 263.144 -84.2645) (xy 263.906 -84.2645) (xy 263.906 -83.7565) (xy 263.144 -83.7565)
				)
			)
		)
	)
)
